(kicad_pcb
	(version 20260206)
	(generator "pcbnew")
	(generator_version "10.0")
	(general
		(thickness 1.6)
		(legacy_teardrops no)
	)
	(paper "A4")
	(title_block
		(title "01162023_DA0F0TEBIF0_F0T_Expander_BD_F_brd_V02_OCP.brd")
		(comment 1 "Grand Teton / footprints 2364-2369 of 9728")
	)
	(layers
		(0 "F.Cu" signal "TOP")
		(4 "In1.Cu" signal "GND")
		(6 "In2.Cu" signal "VCC")
		(8 "In3.Cu" signal "VCC1")
		(10 "In4.Cu" signal "GND1")
		(12 "In5.Cu" signal "IN1")
		(14 "In6.Cu" signal "GND2")
		(16 "In7.Cu" signal "IN2")
		(18 "In8.Cu" signal "GND3")
		(20 "In9.Cu" signal "IN3")
		(22 "In10.Cu" signal "GND4")
		(24 "In11.Cu" signal "IN4")
		(26 "In12.Cu" signal "GND5")
		(28 "In13.Cu" signal "IN5")
		(30 "In14.Cu" signal "GND6")
		(32 "In15.Cu" signal "IN6")
		(34 "In16.Cu" signal "GND7")
		(2 "B.Cu" signal "BOTTOM")
		(9 "F.Adhes" user "F.Adhesive")
		(11 "B.Adhes" user "B.Adhesive")
		(13 "F.Paste" user "Package Geometry/Pastemask Top")
		(15 "B.Paste" user "Package Geometry/Pastemask Bottom")
		(5 "F.SilkS" user "Ref Des/Silkscreen Top")
		(7 "B.SilkS" user "Ref Des/Silkscreen Bottom")
		(1 "F.Mask" user "Board Geometry/Soldermask Top")
		(3 "B.Mask" user "Board Geometry/Soldermask Bottom")
		(17 "Dwgs.User" user "User.Drawings")
		(19 "Cmts.User" user "User.Comments")
		(21 "Eco1.User" user "User.Eco1")
		(23 "Eco2.User" user "User.Eco2")
		(25 "Edge.Cuts" user "Board Geometry/Outline")
		(27 "Margin" user)
		(31 "F.CrtYd" user "Package Geometry/Place Bound Top")
		(29 "B.CrtYd" user "Package Geometry/Place Bound Bottom")
		(35 "F.Fab" user "Ref Des/Assembly Top")
		(33 "B.Fab" user "Ref Des/Assembly Bottom")
	)
	(footprint ""
		(layer "F.Cu")
		(at 257.165094 -346.337382 180)
		(property "Reference" "R6651"
			(at 0 0 180)
			(layer "F.SilkS")
			(hide yes)
			(effects
				(font
					(size 1.27 1.27)
				)
			)
		)
		(property "Value" ""
			(at 0 0 180)
			(layer "F.Fab")
			(effects
				(font
					(size 1.27 1.27)
				)
			)
		)
		(duplicate_pad_numbers_are_jumpers no)
		(fp_line
			(start 0.7874 0.4064)
			(end -0.7874 0.4064)
			(stroke
				(width 0.1524)
				(type default)
			)
			(layer "F.SilkS")
		)
		(fp_line
			(start 0.7874 -0.4064)
			(end 0.7874 0.4064)
			(stroke
				(width 0.1524)
				(type default)
			)
			(layer "F.SilkS")
		)
		(fp_line
			(start -0.7874 0.4064)
			(end -0.7874 -0.4064)
			(stroke
				(width 0.1524)
				(type default)
			)
			(layer "F.SilkS")
		)
		(fp_line
			(start -0.7874 -0.4064)
			(end 0.7874 -0.4064)
			(stroke
				(width 0.1524)
				(type default)
			)
			(layer "F.SilkS")
		)
		(fp_line
			(start 0.67945 0.3048)
			(end 0.120396 0.3048)
			(stroke
				(width 0.1)
				(type default)
			)
			(layer "F.Fab")
		)
		(fp_line
			(start 0.67945 -0.3048)
			(end 0.67945 0.3048)
			(stroke
				(width 0.1)
				(type default)
			)
			(layer "F.Fab")
		)
		(fp_line
			(start 0.12065 -0.2794)
			(end 0.12065 -0.3048)
			(stroke
				(width 0.1)
				(type default)
			)
			(layer "F.Fab")
		)
		(fp_line
			(start 0.12065 -0.3048)
			(end 0.67945 -0.3048)
			(stroke
				(width 0.1)
				(type default)
			)
			(layer "F.Fab")
		)
		(fp_line
			(start 0.120396 0.3048)
			(end 0.120396 0.2794)
			(stroke
				(width 0.1)
				(type default)
			)
			(layer "F.Fab")
		)
		(fp_line
			(start 0.120396 0.2794)
			(end -0.12065 0.2794)
			(stroke
				(width 0.1)
				(type default)
			)
			(layer "F.Fab")
		)
		(fp_line
			(start -0.12065 0.3048)
			(end -0.67945 0.3048)
			(stroke
				(width 0.1)
				(type default)
			)
			(layer "F.Fab")
		)
		(fp_line
			(start -0.12065 0.2794)
			(end -0.12065 0.3048)
			(stroke
				(width 0.1)
				(type default)
			)
			(layer "F.Fab")
		)
		(fp_line
			(start -0.12065 -0.2794)
			(end 0.12065 -0.2794)
			(stroke
				(width 0.1)
				(type default)
			)
			(layer "F.Fab")
		)
		(fp_line
			(start -0.12065 -0.305054)
			(end -0.12065 -0.2794)
			(stroke
				(width 0.1)
				(type default)
			)
			(layer "F.Fab")
		)
		(fp_line
			(start -0.67945 0.3048)
			(end -0.67945 -0.305054)
			(stroke
				(width 0.1)
				(type default)
			)
			(layer "F.Fab")
		)
		(fp_line
			(start -0.67945 -0.305054)
			(end -0.12065 -0.305054)
			(stroke
				(width 0.1)
				(type default)
			)
			(layer "F.Fab")
		)
		(pad "1" smd circle
			(at -0.40005 0 180)
			(size 0 0)
			(layers "F.Cu" "F.Mask" "F.Paste")
			(net "A_HSC_HIGH")
		)
		(pad "2" smd circle
			(at 0.40005 0 180)
			(size 0 0)
			(layers "F.Cu" "F.Mask" "F.Paste")
			(net "GND")
		)
	)
	(footprint ""
		(layer "F.Cu")
		(at 125.419612 -162.003994 90)
		(property "Reference" "PR6901"
			(at 0 0 90)
			(layer "F.SilkS")
			(hide yes)
			(effects
				(font
					(size 1.27 1.27)
				)
			)
		)
		(property "Value" ""
			(at 0 0 90)
			(layer "F.Fab")
			(effects
				(font
					(size 1.27 1.27)
				)
			)
		)
		(duplicate_pad_numbers_are_jumpers no)
		(fp_line
			(start 0.7874 -0.4064)
			(end 0.7874 0.4064)
			(stroke
				(width 0.1524)
				(type default)
			)
			(layer "F.SilkS")
		)
		(fp_line
			(start -0.7874 -0.4064)
			(end 0.7874 -0.4064)
			(stroke
				(width 0.1524)
				(type default)
			)
			(layer "F.SilkS")
		)
		(fp_line
			(start 0.7874 0.4064)
			(end -0.7874 0.4064)
			(stroke
				(width 0.1524)
				(type default)
			)
			(layer "F.SilkS")
		)
		(fp_line
			(start -0.7874 0.4064)
			(end -0.7874 -0.4064)
			(stroke
				(width 0.1524)
				(type default)
			)
			(layer "F.SilkS")
		)
		(fp_line
			(start -0.12065 -0.305054)
			(end -0.12065 -0.2794)
			(stroke
				(width 0.1)
				(type default)
			)
			(layer "F.Fab")
		)
		(fp_line
			(start -0.67945 -0.305054)
			(end -0.12065 -0.305054)
			(stroke
				(width 0.1)
				(type default)
			)
			(layer "F.Fab")
		)
		(fp_line
			(start 0.67945 -0.3048)
			(end 0.67945 0.3048)
			(stroke
				(width 0.1)
				(type default)
			)
			(layer "F.Fab")
		)
		(fp_line
			(start 0.12065 -0.3048)
			(end 0.67945 -0.3048)
			(stroke
				(width 0.1)
				(type default)
			)
			(layer "F.Fab")
		)
		(fp_line
			(start 0.12065 -0.2794)
			(end 0.12065 -0.3048)
			(stroke
				(width 0.1)
				(type default)
			)
			(layer "F.Fab")
		)
		(fp_line
			(start -0.12065 -0.2794)
			(end 0.12065 -0.2794)
			(stroke
				(width 0.1)
				(type default)
			)
			(layer "F.Fab")
		)
		(fp_line
			(start 0.120396 0.2794)
			(end -0.12065 0.2794)
			(stroke
				(width 0.1)
				(type default)
			)
			(layer "F.Fab")
		)
		(fp_line
			(start -0.12065 0.2794)
			(end -0.12065 0.3048)
			(stroke
				(width 0.1)
				(type default)
			)
			(layer "F.Fab")
		)
		(fp_line
			(start 0.67945 0.3048)
			(end 0.120396 0.3048)
			(stroke
				(width 0.1)
				(type default)
			)
			(layer "F.Fab")
		)
		(fp_line
			(start 0.120396 0.3048)
			(end 0.120396 0.2794)
			(stroke
				(width 0.1)
				(type default)
			)
			(layer "F.Fab")
		)
		(fp_line
			(start -0.12065 0.3048)
			(end -0.67945 0.3048)
			(stroke
				(width 0.1)
				(type default)
			)
			(layer "F.Fab")
		)
		(fp_line
			(start -0.67945 0.3048)
			(end -0.67945 -0.305054)
			(stroke
				(width 0.1)
				(type default)
			)
			(layer "F.Fab")
		)
		(pad "1" smd circle
			(at -0.40005 0 90)
			(size 0 0)
			(layers "F.Cu" "F.Mask" "F.Paste")
			(net "P12V_NIC2_CO_IMON_VR")
		)
		(pad "2" smd circle
			(at 0.40005 0 90)
			(size 0 0)
			(layers "F.Cu" "F.Mask" "F.Paste")
			(net "GND")
		)
	)
	(footprint ""
		(layer "F.Cu")
		(at 290.318952 -59.574684 90)
		(property "Reference" "PC565"
			(at 0 0 90)
			(layer "F.SilkS")
			(hide yes)
			(effects
				(font
					(size 1.27 1.27)
				)
			)
		)
		(property "Value" ""
			(at 0 0 90)
			(layer "F.Fab")
			(effects
				(font
					(size 1.27 1.27)
				)
			)
		)
		(duplicate_pad_numbers_are_jumpers no)
		(fp_line
			(start 0.7874 -0.4064)
			(end 0.7874 0.4064)
			(stroke
				(width 0.1524)
				(type default)
			)
			(layer "F.SilkS")
		)
		(fp_line
			(start -0.7874 -0.4064)
			(end 0.7874 -0.4064)
			(stroke
				(width 0.1524)
				(type default)
			)
			(layer "F.SilkS")
		)
		(fp_line
			(start 0.7874 0.4064)
			(end -0.7874 0.4064)
			(stroke
				(width 0.1524)
				(type default)
			)
			(layer "F.SilkS")
		)
		(fp_line
			(start -0.7874 0.4064)
			(end -0.7874 -0.4064)
			(stroke
				(width 0.1524)
				(type default)
			)
			(layer "F.SilkS")
		)
		(fp_line
			(start -0.12065 -0.305054)
			(end -0.12065 -0.2794)
			(stroke
				(width 0.1)
				(type default)
			)
			(layer "F.Fab")
		)
		(fp_line
			(start -0.67945 -0.305054)
			(end -0.12065 -0.305054)
			(stroke
				(width 0.1)
				(type default)
			)
			(layer "F.Fab")
		)
		(fp_line
			(start 0.67945 -0.3048)
			(end 0.67945 0.3048)
			(stroke
				(width 0.1)
				(type default)
			)
			(layer "F.Fab")
		)
		(fp_line
			(start 0.12065 -0.3048)
			(end 0.67945 -0.3048)
			(stroke
				(width 0.1)
				(type default)
			)
			(layer "F.Fab")
		)
		(fp_line
			(start 0.12065 -0.2794)
			(end 0.12065 -0.3048)
			(stroke
				(width 0.1)
				(type default)
			)
			(layer "F.Fab")
		)
		(fp_line
			(start -0.12065 -0.2794)
			(end 0.12065 -0.2794)
			(stroke
				(width 0.1)
				(type default)
			)
			(layer "F.Fab")
		)
		(fp_line
			(start 0.120396 0.2794)
			(end -0.12065 0.2794)
			(stroke
				(width 0.1)
				(type default)
			)
			(layer "F.Fab")
		)
		(fp_line
			(start -0.12065 0.2794)
			(end -0.12065 0.3048)
			(stroke
				(width 0.1)
				(type default)
			)
			(layer "F.Fab")
		)
		(fp_line
			(start 0.67945 0.3048)
			(end 0.120396 0.3048)
			(stroke
				(width 0.1)
				(type default)
			)
			(layer "F.Fab")
		)
		(fp_line
			(start 0.120396 0.3048)
			(end 0.120396 0.2794)
			(stroke
				(width 0.1)
				(type default)
			)
			(layer "F.Fab")
		)
		(fp_line
			(start -0.12065 0.3048)
			(end -0.67945 0.3048)
			(stroke
				(width 0.1)
				(type default)
			)
			(layer "F.Fab")
		)
		(fp_line
			(start -0.67945 0.3048)
			(end -0.67945 -0.305054)
			(stroke
				(width 0.1)
				(type default)
			)
			(layer "F.Fab")
		)
		(pad "1" smd circle
			(at -0.40005 0 90)
			(size 0 0)
			(layers "F.Cu" "F.Mask" "F.Paste")
			(net "P5V_AUX")
		)
		(pad "2" smd circle
			(at 0.40005 0 90)
			(size 0 0)
			(layers "F.Cu" "F.Mask" "F.Paste")
			(net "GND")
		)
	)
	(footprint ""
		(layer "F.Cu")
		(at 327.279 -230.886 90)
		(property "Reference" "U336"
			(at -1.6256 2.21107 90)
			(unlocked yes)
			(layer "F.SilkS")
			(effects
				(font
					(size 0.7874 0.5842)
					(thickness 0.1524)
				)
				(justify left)
			)
		)
		(property "Value" ""
			(at 0 0 90)
			(layer "F.Fab")
			(effects
				(font
					(size 1.27 1.27)
				)
			)
		)
		(duplicate_pad_numbers_are_jumpers no)
		(fp_line
			(start 1.684274 -1.074928)
			(end 1.684274 1.074928)
			(stroke
				(width 0.1524)
				(type default)
			)
			(layer "F.SilkS")
		)
		(fp_line
			(start 0.381 -1.074928)
			(end 1.684274 -1.074928)
			(stroke
				(width 0.1524)
				(type default)
			)
			(layer "F.SilkS")
		)
		(fp_line
			(start -0.381 -1.074928)
			(end 0 -0.625094)
			(stroke
				(width 0.1524)
				(type default)
			)
			(layer "F.SilkS")
		)
		(fp_line
			(start -1.684274 -1.074928)
			(end -0.381 -1.074928)
			(stroke
				(width 0.1524)
				(type default)
			)
			(layer "F.SilkS")
		)
		(fp_line
			(start 0 -0.625094)
			(end 0.381 -1.074928)
			(stroke
				(width 0.1524)
				(type default)
			)
			(layer "F.SilkS")
		)
		(fp_line
			(start 1.684274 1.074928)
			(end -1.684274 1.074928)
			(stroke
				(width 0.1524)
				(type default)
			)
			(layer "F.SilkS")
		)
		(fp_line
			(start -1.684274 1.074928)
			(end -1.684274 -1.074928)
			(stroke
				(width 0.1524)
				(type default)
			)
			(layer "F.SilkS")
		)
		(fp_poly
			(pts
				(xy -2.01803 -1.725422) (xy -2.377186 -1.366012) (xy -1.65862 -1.006856)
			)
			(stroke
				(width 0)
				(type default)
			)
			(fill yes)
			(layer "F.SilkS")
		)
		(fp_line
			(start 0.700024 -1.074928)
			(end -0.700024 -1.074928)
			(stroke
				(width 0.1)
				(type default)
			)
			(layer "F.Fab")
		)
		(fp_line
			(start -0.700024 -1.074928)
			(end -0.700024 1.074928)
			(stroke
				(width 0.1)
				(type default)
			)
			(layer "F.Fab")
		)
		(fp_line
			(start 0.700024 1.074928)
			(end 0.700024 -1.074928)
			(stroke
				(width 0.1)
				(type default)
			)
			(layer "F.Fab")
		)
		(fp_line
			(start -0.700024 1.074928)
			(end 0.700024 1.074928)
			(stroke
				(width 0.1)
				(type default)
			)
			(layer "F.Fab")
		)
		(fp_poly
			(pts
				(xy -2.637282 -0.903986) (xy -2.637282 -0.395986) (xy -1.875282 -0.649986)
			)
			(stroke
				(width 0)
				(type default)
			)
			(fill yes)
			(layer "F.Fab")
		)
		(pad "1" smd rect
			(at -1.100074 -0.649986)
			(size 0.4064 0.9144)
			(layers "F.Cu" "F.Mask" "F.Paste")
			(net "Net_8993")
		)
		(pad "2" smd rect
			(at -1.100074 0)
			(size 0.4064 0.9144)
			(layers "F.Cu" "F.Mask" "F.Paste")
			(net "RST_PEX_SYS_R_N")
		)
		(pad "3" smd rect
			(at -1.100074 0.649986)
			(size 0.4064 0.9144)
			(layers "F.Cu" "F.Mask" "F.Paste")
			(net "GND")
		)
		(pad "4" smd rect
			(at 1.100074 0.649986)
			(size 0.4064 0.9144)
			(layers "F.Cu" "F.Mask" "F.Paste")
			(net "RST_PEX_SYS_BUF_N")
		)
		(pad "5" smd rect
			(at 1.100074 -0.649986)
			(size 0.4064 0.9144)
			(layers "F.Cu" "F.Mask" "F.Paste")
			(net "P3V3_AUX")
		)
	)
	(footprint ""
		(layer "F.Cu")
		(at 217.235786 -212.206586)
		(property "Reference" "R5718"
			(at 0 0 0)
			(layer "F.SilkS")
			(hide yes)
			(effects
				(font
					(size 1.27 1.27)
				)
			)
		)
		(property "Value" ""
			(at 0 0 0)
			(layer "F.Fab")
			(effects
				(font
					(size 1.27 1.27)
				)
			)
		)
		(duplicate_pad_numbers_are_jumpers no)
		(fp_line
			(start -0.7874 -0.4064)
			(end 0.7874 -0.4064)
			(stroke
				(width 0.1524)
				(type default)
			)
			(layer "F.SilkS")
		)
		(fp_line
			(start -0.7874 0.4064)
			(end -0.7874 -0.4064)
			(stroke
				(width 0.1524)
				(type default)
			)
			(layer "F.SilkS")
		)
		(fp_line
			(start 0.7874 -0.4064)
			(end 0.7874 0.4064)
			(stroke
				(width 0.1524)
				(type default)
			)
			(layer "F.SilkS")
		)
		(fp_line
			(start 0.7874 0.4064)
			(end -0.7874 0.4064)
			(stroke
				(width 0.1524)
				(type default)
			)
			(layer "F.SilkS")
		)
		(fp_line
			(start -0.67945 -0.305054)
			(end -0.12065 -0.305054)
			(stroke
				(width 0.1)
				(type default)
			)
			(layer "F.Fab")
		)
		(fp_line
			(start -0.67945 0.3048)
			(end -0.67945 -0.305054)
			(stroke
				(width 0.1)
				(type default)
			)
			(layer "F.Fab")
		)
		(fp_line
			(start -0.12065 -0.305054)
			(end -0.12065 -0.2794)
			(stroke
				(width 0.1)
				(type default)
			)
			(layer "F.Fab")
		)
		(fp_line
			(start -0.12065 -0.2794)
			(end 0.12065 -0.2794)
			(stroke
				(width 0.1)
				(type default)
			)
			(layer "F.Fab")
		)
		(fp_line
			(start -0.12065 0.2794)
			(end -0.12065 0.3048)
			(stroke
				(width 0.1)
				(type default)
			)
			(layer "F.Fab")
		)
		(fp_line
			(start -0.12065 0.3048)
			(end -0.67945 0.3048)
			(stroke
				(width 0.1)
				(type default)
			)
			(layer "F.Fab")
		)
		(fp_line
			(start 0.120396 0.2794)
			(end -0.12065 0.2794)
			(stroke
				(width 0.1)
				(type default)
			)
			(layer "F.Fab")
		)
		(fp_line
			(start 0.120396 0.3048)
			(end 0.120396 0.2794)
			(stroke
				(width 0.1)
				(type default)
			)
			(layer "F.Fab")
		)
		(fp_line
			(start 0.12065 -0.3048)
			(end 0.67945 -0.3048)
			(stroke
				(width 0.1)
				(type default)
			)
			(layer "F.Fab")
		)
		(fp_line
			(start 0.12065 -0.2794)
			(end 0.12065 -0.3048)
			(stroke
				(width 0.1)
				(type default)
			)
			(layer "F.Fab")
		)
		(fp_line
			(start 0.67945 -0.3048)
			(end 0.67945 0.3048)
			(stroke
				(width 0.1)
				(type default)
			)
			(layer "F.Fab")
		)
		(fp_line
			(start 0.67945 0.3048)
			(end 0.120396 0.3048)
			(stroke
				(width 0.1)
				(type default)
			)
			(layer "F.Fab")
		)
		(pad "1" smd circle
			(at -0.40005 0)
			(size 0 0)
			(layers "F.Cu" "F.Mask" "F.Paste")
			(net "RST_BIC_I2C9_SSD_MUX0_R_N")
		)
		(pad "2" smd circle
			(at 0.40005 0)
			(size 0 0)
			(layers "F.Cu" "F.Mask" "F.Paste")
			(net "RST_BIC_I2C9_SSD_MUX0_N")
		)
	)
	(footprint ""
		(layer "F.Cu")
		(at 284.443678 -44.87291)
		(property "Reference" "R606"
			(at 0 0 0)
			(layer "F.SilkS")
			(hide yes)
			(effects
				(font
					(size 1.27 1.27)
				)
			)
		)
		(property "Value" ""
			(at 0 0 0)
			(layer "F.Fab")
			(effects
				(font
					(size 1.27 1.27)
				)
			)
		)
		(duplicate_pad_numbers_are_jumpers no)
		(fp_line
			(start -0.7874 -0.4064)
			(end 0.7874 -0.4064)
			(stroke
				(width 0.1524)
				(type default)
			)
			(layer "F.SilkS")
		)
		(fp_line
			(start -0.7874 0.4064)
			(end -0.7874 -0.4064)
			(stroke
				(width 0.1524)
				(type default)
			)
			(layer "F.SilkS")
		)
		(fp_line
			(start 0.7874 -0.4064)
			(end 0.7874 0.4064)
			(stroke
				(width 0.1524)
				(type default)
			)
			(layer "F.SilkS")
		)
		(fp_line
			(start 0.7874 0.4064)
			(end -0.7874 0.4064)
			(stroke
				(width 0.1524)
				(type default)
			)
			(layer "F.SilkS")
		)
		(fp_line
			(start -0.67945 -0.305054)
			(end -0.12065 -0.305054)
			(stroke
				(width 0.1)
				(type default)
			)
			(layer "F.Fab")
		)
		(fp_line
			(start -0.67945 0.3048)
			(end -0.67945 -0.305054)
			(stroke
				(width 0.1)
				(type default)
			)
			(layer "F.Fab")
		)
		(fp_line
			(start -0.12065 -0.305054)
			(end -0.12065 -0.2794)
			(stroke
				(width 0.1)
				(type default)
			)
			(layer "F.Fab")
		)
		(fp_line
			(start -0.12065 -0.2794)
			(end 0.12065 -0.2794)
			(stroke
				(width 0.1)
				(type default)
			)
			(layer "F.Fab")
		)
		(fp_line
			(start -0.12065 0.2794)
			(end -0.12065 0.3048)
			(stroke
				(width 0.1)
				(type default)
			)
			(layer "F.Fab")
		)
		(fp_line
			(start -0.12065 0.3048)
			(end -0.67945 0.3048)
			(stroke
				(width 0.1)
				(type default)
			)
			(layer "F.Fab")
		)
		(fp_line
			(start 0.120396 0.2794)
			(end -0.12065 0.2794)
			(stroke
				(width 0.1)
				(type default)
			)
			(layer "F.Fab")
		)
		(fp_line
			(start 0.120396 0.3048)
			(end 0.120396 0.2794)
			(stroke
				(width 0.1)
				(type default)
			)
			(layer "F.Fab")
		)
		(fp_line
			(start 0.12065 -0.3048)
			(end 0.67945 -0.3048)
			(stroke
				(width 0.1)
				(type default)
			)
			(layer "F.Fab")
		)
		(fp_line
			(start 0.12065 -0.2794)
			(end 0.12065 -0.3048)
			(stroke
				(width 0.1)
				(type default)
			)
			(layer "F.Fab")
		)
		(fp_line
			(start 0.67945 -0.3048)
			(end 0.67945 0.3048)
			(stroke
				(width 0.1)
				(type default)
			)
			(layer "F.Fab")
		)
		(fp_line
			(start 0.67945 0.3048)
			(end 0.120396 0.3048)
			(stroke
				(width 0.1)
				(type default)
			)
			(layer "F.Fab")
		)
		(pad "1" smd circle
			(at -0.40005 0)
			(size 0 0)
			(layers "F.Cu" "F.Mask" "F.Paste")
			(net "SSD9_ADC_A0")
		)
		(pad "2" smd circle
			(at 0.40005 0)
			(size 0 0)
			(layers "F.Cu" "F.Mask" "F.Paste")
			(net "P3V3_AUX")
		)
	)
)
